# T6G (Grand Teton) — schematic netlist excerpt (pin names and nets, part order shuffled) for the footprints in the layout excerpt that follows; sources: Cadence DE-HDL packaged netlist, KiCad conversion of 04192023_DAF0TMB3IC0_F0TG_MB_C_brd_V02_OCP.brd

PC531  Q_CAPP  390UF 2.5V 20% ALUM  pkg SMLF  page 225 : A = PVDD11_S3_P1 ; B = GND
C605  Q_CAP  0.001UF 50V 10% X7R  pkg C0402  page 172 : A = HDT_HDR_TDI ; B = GND

(kicad_pcb
	(version 20260206)
	(generator "pcbnew")
	(generator_version "10.0")
	(general
		(thickness 1.6)
		(legacy_teardrops no)
	)
	(paper "A4")
	(title_block
		(title "04192023_DAF0TMB3IC0_F0TG_MB_C_brd_V02_OCP.brd")
		(comment 1 "Grand Teton / footprints 2368-2369 of 8354")
	)
	(layers
		(0 "F.Cu" signal "TOP")
		(4 "In1.Cu" signal "GND")
		(6 "In2.Cu" signal "IN1")
		(8 "In3.Cu" signal "GND1")
		(10 "In4.Cu" signal "IN2")
		(12 "In5.Cu" signal "GND2")
		(14 "In6.Cu" signal "IN3")
		(16 "In7.Cu" signal "GND3")
		(18 "In8.Cu" signal "VCC")
		(20 "In9.Cu" signal "VCC1")
		(22 "In10.Cu" signal "GND4")
		(24 "In11.Cu" signal "IN4")
		(26 "In12.Cu" signal "GND5")
		(28 "In13.Cu" signal "IN5")
		(30 "In14.Cu" signal "GND6")
		(32 "In15.Cu" signal "IN6")
		(34 "In16.Cu" signal "GND7")
		(2 "B.Cu" signal "BOTTOM")
		(9 "F.Adhes" user "F.Adhesive")
		(11 "B.Adhes" user "B.Adhesive")
		(13 "F.Paste" user "Package Geometry/Pastemask Top")
		(15 "B.Paste" user "Package Geometry/Pastemask Bottom")
		(5 "F.SilkS" user "Ref Des/Silkscreen Top")
		(7 "B.SilkS" user "Ref Des/Silkscreen Bottom")
		(1 "F.Mask" user "Board Geometry/Soldermask Top")
		(3 "B.Mask" user "Board Geometry/Soldermask Bottom")
		(17 "Dwgs.User" user "User.Drawings")
		(19 "Cmts.User" user "User.Comments")
		(21 "Eco1.User" user "User.Eco1")
		(23 "Eco2.User" user "User.Eco2")
		(25 "Edge.Cuts" user "Board Geometry/Outline")
		(27 "Margin" user)
		(31 "F.CrtYd" user "Package Geometry/Place Bound Top")
		(29 "B.CrtYd" user "Package Geometry/Place Bound Bottom")
		(35 "F.Fab" user "Ref Des/Assembly Top")
		(33 "B.Fab" user "Ref Des/Assembly Bottom")
	)
	(footprint ""
		(layer "F.Cu")
		(at 182.026306 -332.744572 -90)
		(property "Reference" "PC531"
			(at -4.13512 9.547352 90)
			(unlocked yes)
			(layer "F.SilkS")
			(effects
				(font
					(size 0.7874 0.5842)
					(thickness 0.1524)
				)
				(justify left)
			)
		)
		(property "Value" ""
			(at 0 0 270)
			(layer "F.Fab")
			(effects
				(font
					(size 1.27 1.27)
				)
			)
		)
		(duplicate_pad_numbers_are_jumpers no)
		(fp_line
			(start -1.988058 2.750058)
			(end 2.750058 2.750058)
			(stroke
				(width 0.1524)
				(type default)
			)
			(layer "F.SilkS")
		)
		(fp_line
			(start 2.750058 2.750058)
			(end 2.750058 0.9398)
			(stroke
				(width 0.1524)
				(type default)
			)
			(layer "F.SilkS")
		)
		(fp_line
			(start -2.750058 1.988058)
			(end -1.988058 2.750058)
			(stroke
				(width 0.1524)
				(type default)
			)
			(layer "F.SilkS")
		)
		(fp_line
			(start -2.750058 0.9398)
			(end -2.750058 1.988058)
			(stroke
				(width 0.1524)
				(type default)
			)
			(layer "F.SilkS")
		)
		(fp_line
			(start 2.750058 -0.9398)
			(end 2.750058 -2.750058)
			(stroke
				(width 0.1524)
				(type default)
			)
			(layer "F.SilkS")
		)
		(fp_line
			(start -2.750058 -1.988058)
			(end -2.750058 -0.9398)
			(stroke
				(width 0.1524)
				(type default)
			)
			(layer "F.SilkS")
		)
		(fp_line
			(start -1.988058 -2.750058)
			(end -2.750058 -1.988058)
			(stroke
				(width 0.1524)
				(type default)
			)
			(layer "F.SilkS")
		)
		(fp_line
			(start 2.750058 -2.750058)
			(end -1.988058 -2.750058)
			(stroke
				(width 0.1524)
				(type default)
			)
			(layer "F.SilkS")
		)
		(fp_line
			(start -2.750058 2.750058)
			(end 2.750058 2.750058)
			(stroke
				(width 0.1)
				(type default)
			)
			(layer "F.Fab")
		)
		(fp_line
			(start 2.750058 2.750058)
			(end 2.750058 -2.750058)
			(stroke
				(width 0.1)
				(type default)
			)
			(layer "F.Fab")
		)
		(fp_line
			(start -2.750058 -2.750058)
			(end -2.750058 2.750058)
			(stroke
				(width 0.1)
				(type default)
			)
			(layer "F.Fab")
		)
		(fp_line
			(start 2.750058 -2.750058)
			(end -2.750058 -2.750058)
			(stroke
				(width 0.1)
				(type default)
			)
			(layer "F.Fab")
		)
		(pad "1" smd rect
			(at -2.199894 0)
			(size 1.6002 3.0226)
			(layers "F.Cu" "F.Mask" "F.Paste")
			(net "PVDD11_S3_P1")
		)
		(pad "2" smd rect
			(at 2.199894 0)
			(size 1.6002 3.0226)
			(layers "F.Cu" "F.Mask" "F.Paste")
			(net "GND")
		)
	)
	(footprint ""
		(layer "F.Cu")
		(at 384.465576 -56.81345 -90)
		(property "Reference" "C605"
			(at 0 0 270)
			(layer "F.SilkS")
			(hide yes)
			(effects
				(font
					(size 1.27 1.27)
				)
			)
		)
		(property "Value" ""
			(at 0 0 270)
			(layer "F.Fab")
			(effects
				(font
					(size 1.27 1.27)
				)
			)
		)
		(duplicate_pad_numbers_are_jumpers no)
		(fp_line
			(start -0.7874 0.4064)
			(end -0.7874 -0.4064)
			(stroke
				(width 0.1524)
				(type default)
			)
			(layer "F.SilkS")
		)
		(fp_line
			(start 0.7874 0.4064)
			(end -0.7874 0.4064)
			(stroke
				(width 0.1524)
				(type default)
			)
			(layer "F.SilkS")
		)
		(fp_line
			(start -0.7874 -0.4064)
			(end 0.7874 -0.4064)
			(stroke
				(width 0.1524)
				(type default)
			)
			(layer "F.SilkS")
		)
		(fp_line
			(start 0.7874 -0.4064)
			(end 0.7874 0.4064)
			(stroke
				(width 0.1524)
				(type default)
			)
			(layer "F.SilkS")
		)
		(fp_line
			(start -0.67945 0.3048)
			(end -0.67945 -0.305054)
			(stroke
				(width 0.1)
				(type default)
			)
			(layer "F.Fab")
		)
		(fp_line
			(start -0.12065 0.3048)
			(end -0.67945 0.3048)
			(stroke
				(width 0.1)
				(type default)
			)
			(layer "F.Fab")
		)
		(fp_line
			(start 0.120396 0.3048)
			(end 0.120396 0.2794)
			(stroke
				(width 0.1)
				(type default)
			)
			(layer "F.Fab")
		)
		(fp_line
			(start 0.67945 0.3048)
			(end 0.120396 0.3048)
			(stroke
				(width 0.1)
				(type default)
			)
			(layer "F.Fab")
		)
		(fp_line
			(start -0.12065 0.2794)
			(end -0.12065 0.3048)
			(stroke
				(width 0.1)
				(type default)
			)
			(layer "F.Fab")
		)
		(fp_line
			(start 0.120396 0.2794)
			(end -0.12065 0.2794)
			(stroke
				(width 0.1)
				(type default)
			)
			(layer "F.Fab")
		)
		(fp_line
			(start -0.12065 -0.2794)
			(end 0.12065 -0.2794)
			(stroke
				(width 0.1)
				(type default)
			)
			(layer "F.Fab")
		)
		(fp_line
			(start 0.12065 -0.2794)
			(end 0.12065 -0.3048)
			(stroke
				(width 0.1)
				(type default)
			)
			(layer "F.Fab")
		)
		(fp_line
			(start 0.12065 -0.3048)
			(end 0.67945 -0.3048)
			(stroke
				(width 0.1)
				(type default)
			)
			(layer "F.Fab")
		)
		(fp_line
			(start 0.67945 -0.3048)
			(end 0.67945 0.3048)
			(stroke
				(width 0.1)
				(type default)
			)
			(layer "F.Fab")
		)
		(fp_line
			(start -0.67945 -0.305054)
			(end -0.12065 -0.305054)
			(stroke
				(width 0.1)
				(type default)
			)
			(layer "F.Fab")
		)
		(fp_line
			(start -0.12065 -0.305054)
			(end -0.12065 -0.2794)
			(stroke
				(width 0.1)
				(type default)
			)
			(layer "F.Fab")
		)
		(pad "1" smd circle
			(at -0.40005 0 270)
			(size 0 0)
			(layers "F.Cu" "F.Mask" "F.Paste")
			(net "HDT_HDR_TDI")
		)
		(pad "2" smd circle
			(at 0.40005 0 270)
			(size 0 0)
			(layers "F.Cu" "F.Mask" "F.Paste")
			(net "GND")
		)
	)
)
